(kicad_pcb
	(version 20260206)
	(generator "pcbnew")
	(generator_version "10.0")
	(general
		(thickness 1.6)
		(legacy_teardrops no)
	)
	(paper "A4")
	(title_block
		(title "pdpb — Lightning_PDPB_BRD.brd")
		(comment 1 "Lightning (Wiwynn / Facebook NVMe JBOF) / footprints 773-779 of 1140")
	)
	(layers
		(0 "F.Cu" signal "TOP")
		(4 "In1.Cu" signal "L2GND")
		(6 "In2.Cu" signal "L3")
		(8 "In3.Cu" signal "L4VCC")
		(10 "In4.Cu" signal "L5VCC")
		(12 "In5.Cu" signal "L6")
		(14 "In6.Cu" signal "L7GND")
		(2 "B.Cu" signal "BOTTOM")
		(9 "F.Adhes" user "F.Adhesive")
		(11 "B.Adhes" user "B.Adhesive")
		(13 "F.Paste" user "Package Geometry/Pastemask Top")
		(15 "B.Paste" user "Package Geometry/Pastemask Bottom")
		(5 "F.SilkS" user "Ref Des/Silkscreen Top")
		(7 "B.SilkS" user "Ref Des/Silkscreen Bottom")
		(1 "F.Mask" user "Board Geometry/Soldermask Top")
		(3 "B.Mask" user "Board Geometry/Soldermask Bottom")
		(17 "Dwgs.User" user "User.Drawings")
		(19 "Cmts.User" user "User.Comments")
		(21 "Eco1.User" user "User.Eco1")
		(23 "Eco2.User" user "User.Eco2")
		(25 "Edge.Cuts" user "Board Geometry/Outline")
		(27 "Margin" user)
		(31 "F.CrtYd" user "Package Geometry/Place Bound Top")
		(29 "B.CrtYd" user "Package Geometry/Place Bound Bottom")
		(35 "F.Fab" user "Ref Des/Assembly Top")
		(33 "B.Fab" user "Ref Des/Assembly Bottom")
	)
	(footprint ""
		(layer "F.Cu")
		(at 21.231606 -368.1095 180)
		(property "Reference" "R9923"
			(at 0 0 180)
			(layer "F.SilkS")
			(hide yes)
			(effects
				(font
					(size 1.27 1.27)
				)
			)
		)
		(property "Value" "47KR2J-2-GP"
			(at 0.064008 -3.993896 180)
			(unlocked yes)
			(layer "F.Fab")
			(hide yes)
			(effects
				(font
					(size 1.016 1.016)
					(thickness 0.1524)
				)
			)
		)
		(property "Device Type" "R402H16"
			(at 0.064008 -5.517896 180)
			(unlocked yes)
			(layer "F.Fab")
			(hide yes)
			(effects
				(font
					(size 1.016 1.016)
					(thickness 0.1524)
				)
			)
		)
		(duplicate_pad_numbers_are_jumpers no)
		(fp_line
			(start 0.508 -0.9398)
			(end -0.508 -0.9398)
			(stroke
				(width 0.1524)
				(type default)
			)
			(layer "F.SilkS")
		)
		(fp_line
			(start -0.508 -0.9398)
			(end -0.508 0.9398)
			(stroke
				(width 0.1524)
				(type default)
			)
			(layer "F.SilkS")
		)
		(fp_rect
			(start -0.508 0.9398)
			(end 0.508 -0.9398)
			(stroke
				(width 0)
				(type default)
			)
			(fill no)
			(layer "F.CrtYd")
		)
		(fp_rect
			(start -0.508 0.9398)
			(end 0.508 -0.9398)
			(stroke
				(width 0)
				(type default)
			)
			(fill no)
			(layer "F.Fab")
		)
		(pad "1" smd custom
			(at 0 -0.4445 180)
			(size 0.1397 0.1397)
			(layers "F.Cu" "F.Mask" "F.Paste")
			(net "P3V3")
			(options
				(clearance outline)
				(anchor circle)
			)
			(primitives
				(gr_poly
					(pts
						(arc
							(start -0.1778 -0.2794)
							(mid -0.249642 -0.249642)
							(end -0.2794 -0.1778)
						)
						(arc
							(start -0.2794 0.1778)
							(mid -0.249642 0.249642)
							(end -0.1778 0.2794)
						)
						(arc
							(start 0.1778 0.2794)
							(mid 0.249642 0.249642)
							(end 0.2794 0.1778)
						)
						(arc
							(start 0.2794 -0.1778)
							(mid 0.249642 -0.249642)
							(end 0.1778 -0.2794)
						)
					)
					(width 0)
					(fill yes)
				)
			)
		)
		(pad "2" smd custom
			(at 0 0.4445 180)
			(size 0.1397 0.1397)
			(layers "F.Cu" "F.Mask" "F.Paste")
			(net "ATTN_LED_DR11_N")
			(options
				(clearance outline)
				(anchor circle)
			)
			(primitives
				(gr_poly
					(pts
						(arc
							(start -0.1778 -0.2794)
							(mid -0.249642 -0.249642)
							(end -0.2794 -0.1778)
						)
						(arc
							(start -0.2794 0.1778)
							(mid -0.249642 0.249642)
							(end -0.1778 0.2794)
						)
						(arc
							(start 0.1778 0.2794)
							(mid 0.249642 0.249642)
							(end 0.2794 0.1778)
						)
						(arc
							(start 0.2794 -0.1778)
							(mid 0.249642 -0.249642)
							(end 0.1778 -0.2794)
						)
					)
					(width 0)
					(fill yes)
				)
			)
		)
	)
	(footprint ""
		(layer "F.Cu")
		(at 27.0002 -110.744 180)
		(property "Reference" "PC1211"
			(at 0 0 180)
			(layer "F.SilkS")
			(hide yes)
			(effects
				(font
					(size 1.27 1.27)
				)
			)
		)
		(property "Value" "SC22U25V6KX-GP-U"
			(at -2.860802 -5.279644 180)
			(unlocked yes)
			(layer "F.Fab")
			(hide yes)
			(effects
				(font
					(size 1.016 1.016)
					(thickness 0.1524)
				)
			)
		)
		(property "Device Type" "C1206-TO0D3H75"
			(at -2.860802 -6.803644 180)
			(unlocked yes)
			(layer "F.Fab")
			(hide yes)
			(effects
				(font
					(size 1.016 1.016)
					(thickness 0.1524)
				)
			)
		)
		(duplicate_pad_numbers_are_jumpers no)
		(fp_line
			(start 1.3081 2.3749)
			(end -1.3081 2.3749)
			(stroke
				(width 0.1524)
				(type default)
			)
			(layer "F.SilkS")
		)
		(fp_line
			(start 1.3081 -2.3749)
			(end 1.3081 2.3749)
			(stroke
				(width 0.1524)
				(type default)
			)
			(layer "F.SilkS")
		)
		(fp_line
			(start -1.3081 2.3749)
			(end -1.3081 -2.3749)
			(stroke
				(width 0.1524)
				(type default)
			)
			(layer "F.SilkS")
		)
		(fp_line
			(start -1.3081 -2.3749)
			(end 1.3081 -2.3749)
			(stroke
				(width 0.1524)
				(type default)
			)
			(layer "F.SilkS")
		)
		(fp_rect
			(start -0.8001 1.6002)
			(end 0.8001 -1.6002)
			(stroke
				(width 0)
				(type default)
			)
			(fill no)
			(layer "F.CrtYd")
		)
		(fp_poly
			(pts
				(xy -1.5621 2.4511) (xy -1.5621 1.6002) (xy 0.8001 1.6002) (xy 0.8001 -1.6002) (xy -0.8001 -1.6002)
				(xy -0.8001 1.5875) (xy -1.5621 1.5875) (xy -1.5621 -2.4511) (xy 1.5621 -2.4511) (xy 1.5621 2.4511)
			)
			(stroke
				(width 0)
				(type default)
			)
			(fill no)
			(layer "F.CrtYd")
		)
		(fp_rect
			(start -1.5621 2.4511)
			(end 1.5621 -2.4511)
			(stroke
				(width 0)
				(type default)
			)
			(fill no)
			(layer "F.Fab")
		)
		(pad "1" smd rect
			(at 0 -1.392936 180)
			(size 2.1082 1.4478)
			(layers "F.Cu" "F.Mask" "F.Paste")
			(net "P12V_SSD13")
		)
		(pad "2" smd rect
			(at 0 1.392936 180)
			(size 2.1082 1.4478)
			(layers "F.Cu" "F.Mask" "F.Paste")
			(net "GND")
		)
	)
	(footprint ""
		(layer "F.Cu")
		(at 79.0956 -107.3404 90)
		(property "Reference" "FB10"
			(at 0 0 90)
			(layer "F.SilkS")
			(hide yes)
			(effects
				(font
					(size 1.27 1.27)
				)
			)
		)
		(property "Value" "BLM21PG331SN1D-2-GP"
			(at 0 -4.2418 90)
			(unlocked yes)
			(layer "F.Fab")
			(hide yes)
			(effects
				(font
					(size 1.016 1.016)
					(thickness 0.1524)
				)
			)
		)
		(property "Device Type" "L805H42"
			(at 0 -5.7912 90)
			(unlocked yes)
			(layer "F.Fab")
			(hide yes)
			(effects
				(font
					(size 1.016 1.016)
					(thickness 0.1524)
				)
			)
		)
		(duplicate_pad_numbers_are_jumpers no)
		(fp_line
			(start 0.889 -1.7018)
			(end 0.889 1.7018)
			(stroke
				(width 0.1524)
				(type default)
			)
			(layer "F.SilkS")
		)
		(fp_line
			(start -0.889 -1.7018)
			(end 0.889 -1.7018)
			(stroke
				(width 0.1524)
				(type default)
			)
			(layer "F.SilkS")
		)
		(fp_line
			(start 0.889 1.7018)
			(end -0.889 1.7018)
			(stroke
				(width 0.1524)
				(type default)
			)
			(layer "F.SilkS")
		)
		(fp_line
			(start -0.889 1.7018)
			(end -0.889 -1.7018)
			(stroke
				(width 0.1524)
				(type default)
			)
			(layer "F.SilkS")
		)
		(fp_rect
			(start -0.9652 1.778)
			(end 0.9652 -1.778)
			(stroke
				(width 0)
				(type default)
			)
			(fill no)
			(layer "F.CrtYd")
		)
		(fp_rect
			(start -0.9652 1.778)
			(end 0.9652 -1.778)
			(stroke
				(width 0)
				(type default)
			)
			(fill no)
			(layer "F.Fab")
		)
		(pad "1" smd rect
			(at 0 -0.9652 90)
			(size 1.397 1.143)
			(layers "F.Cu" "F.Mask" "F.Paste")
			(net "P3V3")
		)
		(pad "2" smd rect
			(at 0 0.9652 90)
			(size 1.397 1.143)
			(layers "F.Cu" "F.Mask" "F.Paste")
			(net "VDD_DIFF_4")
		)
	)
	(footprint ""
		(layer "F.Cu")
		(at 231.267 -434.467 180)
		(property "Reference" "PC1263"
			(at 0 0 180)
			(layer "F.SilkS")
			(hide yes)
			(effects
				(font
					(size 1.27 1.27)
				)
			)
		)
		(property "Value" "SC1U16V3KX-5GP"
			(at 0 -2.8194 180)
			(unlocked yes)
			(layer "F.Fab")
			(hide yes)
			(effects
				(font
					(size 1.016 1.016)
					(thickness 0.1524)
				)
			)
		)
		(property "Device Type" "C603H36"
			(at 0 -4.3434 180)
			(unlocked yes)
			(layer "F.Fab")
			(hide yes)
			(effects
				(font
					(size 1.016 1.016)
					(thickness 0.1524)
				)
			)
		)
		(duplicate_pad_numbers_are_jumpers no)
		(fp_line
			(start 0.508 0)
			(end -0.508 0)
			(stroke
				(width 0.2032)
				(type default)
			)
			(layer "F.SilkS")
		)
		(fp_rect
			(start -0.5842 1.3335)
			(end 0.5842 -1.3335)
			(stroke
				(width 0)
				(type default)
			)
			(fill no)
			(layer "F.CrtYd")
		)
		(fp_rect
			(start -0.5842 1.3335)
			(end 0.5842 -1.3335)
			(stroke
				(width 0)
				(type default)
			)
			(fill no)
			(layer "F.Fab")
		)
		(pad "1" smd custom
			(at 0 -0.762 180)
			(size 0.2159 0.2159)
			(layers "F.Cu" "F.Mask" "F.Paste")
			(net "P3V3_VRG5")
			(options
				(clearance outline)
				(anchor circle)
			)
			(primitives
				(gr_poly
					(pts
						(arc
							(start -0.3302 -0.4318)
							(mid -0.402042 -0.402042)
							(end -0.4318 -0.3302)
						)
						(arc
							(start -0.4318 0.3302)
							(mid -0.402042 0.402042)
							(end -0.3302 0.4318)
						)
						(arc
							(start 0.3302 0.4318)
							(mid 0.402042 0.402042)
							(end 0.4318 0.3302)
						)
						(arc
							(start 0.4318 -0.3302)
							(mid 0.402042 -0.402042)
							(end 0.3302 -0.4318)
						)
					)
					(width 0)
					(fill yes)
				)
			)
		)
		(pad "2" smd custom
			(at 0 0.762 180)
			(size 0.2159 0.2159)
			(layers "F.Cu" "F.Mask" "F.Paste")
			(net "GND")
			(options
				(clearance outline)
				(anchor circle)
			)
			(primitives
				(gr_poly
					(pts
						(arc
							(start -0.3302 -0.4318)
							(mid -0.402042 -0.402042)
							(end -0.4318 -0.3302)
						)
						(arc
							(start -0.4318 0.3302)
							(mid -0.402042 0.402042)
							(end -0.3302 0.4318)
						)
						(arc
							(start 0.3302 0.4318)
							(mid 0.402042 0.402042)
							(end 0.4318 0.3302)
						)
						(arc
							(start 0.4318 -0.3302)
							(mid 0.402042 -0.402042)
							(end 0.3302 -0.4318)
						)
					)
					(width 0)
					(fill yes)
				)
			)
		)
	)
	(footprint ""
		(layer "F.Cu")
		(at 42.29862 -248.851166 90)
		(property "Reference" "R9941"
			(at 0 0 90)
			(layer "F.SilkS")
			(hide yes)
			(effects
				(font
					(size 1.27 1.27)
				)
			)
		)
		(property "Value" "4K7R2J-2-GP"
			(at 0.064008 -3.993896 90)
			(unlocked yes)
			(layer "F.Fab")
			(hide yes)
			(effects
				(font
					(size 1.016 1.016)
					(thickness 0.1524)
				)
			)
		)
		(property "Device Type" "R402H16"
			(at 0.064008 -5.517896 90)
			(unlocked yes)
			(layer "F.Fab")
			(hide yes)
			(effects
				(font
					(size 1.016 1.016)
					(thickness 0.1524)
				)
			)
		)
		(duplicate_pad_numbers_are_jumpers no)
		(fp_line
			(start 0.508 -0.9398)
			(end -0.508 -0.9398)
			(stroke
				(width 0.1524)
				(type default)
			)
			(layer "F.SilkS")
		)
		(fp_line
			(start -0.508 -0.9398)
			(end -0.508 0.9398)
			(stroke
				(width 0.1524)
				(type default)
			)
			(layer "F.SilkS")
		)
		(fp_rect
			(start -0.508 0.9398)
			(end 0.508 -0.9398)
			(stroke
				(width 0)
				(type default)
			)
			(fill no)
			(layer "F.CrtYd")
		)
		(fp_rect
			(start -0.508 0.9398)
			(end 0.508 -0.9398)
			(stroke
				(width 0)
				(type default)
			)
			(fill no)
			(layer "F.Fab")
		)
		(pad "1" smd custom
			(at 0 -0.4445 90)
			(size 0.1397 0.1397)
			(layers "F.Cu" "F.Mask" "F.Paste")
			(net "P3V3")
			(options
				(clearance outline)
				(anchor circle)
			)
			(primitives
				(gr_poly
					(pts
						(arc
							(start -0.1778 -0.2794)
							(mid -0.249642 -0.249642)
							(end -0.2794 -0.1778)
						)
						(arc
							(start -0.2794 0.1778)
							(mid -0.249642 0.249642)
							(end -0.1778 0.2794)
						)
						(arc
							(start 0.1778 0.2794)
							(mid 0.249642 0.249642)
							(end 0.2794 0.1778)
						)
						(arc
							(start 0.2794 -0.1778)
							(mid 0.249642 -0.249642)
							(end 0.1778 -0.2794)
						)
					)
					(width 0)
					(fill yes)
				)
			)
		)
		(pad "2" smd custom
			(at 0 0.4445 90)
			(size 0.1397 0.1397)
			(layers "F.Cu" "F.Mask" "F.Paste")
			(net "ATTN_LED_DR7_MOS_N")
			(options
				(clearance outline)
				(anchor circle)
			)
			(primitives
				(gr_poly
					(pts
						(arc
							(start -0.1778 -0.2794)
							(mid -0.249642 -0.249642)
							(end -0.2794 -0.1778)
						)
						(arc
							(start -0.2794 0.1778)
							(mid -0.249642 0.249642)
							(end -0.1778 0.2794)
						)
						(arc
							(start 0.1778 0.2794)
							(mid 0.249642 0.249642)
							(end 0.2794 0.1778)
						)
						(arc
							(start 0.2794 -0.1778)
							(mid 0.249642 -0.249642)
							(end 0.1778 -0.2794)
						)
					)
					(width 0)
					(fill yes)
				)
			)
		)
	)
	(footprint ""
		(layer "F.Cu")
		(at 207.096106 -498.654578)
		(property "Reference" "R9775"
			(at 0 0 0)
			(layer "F.SilkS")
			(hide yes)
			(effects
				(font
					(size 1.27 1.27)
				)
			)
		)
		(property "Value" "2K2R5F-GP"
			(at 0 -8.9535 0)
			(unlocked yes)
			(layer "F.Fab")
			(hide yes)
			(effects
				(font
					(size 1.27 1.016)
					(thickness 0.1524)
				)
			)
		)
		(property "Device Type" "R805H24"
			(at 0 -10.6299 0)
			(unlocked yes)
			(layer "F.Fab")
			(hide yes)
			(effects
				(font
					(size 1.27 1.016)
					(thickness 0.1524)
				)
			)
		)
		(duplicate_pad_numbers_are_jumpers no)
		(fp_line
			(start -0.889 -1.7018)
			(end -0.889 0.2794)
			(stroke
				(width 0.1524)
				(type default)
			)
			(layer "F.SilkS")
		)
		(fp_line
			(start -0.889 0.0762)
			(end -0.889 1.7018)
			(stroke
				(width 0.1524)
				(type default)
			)
			(layer "F.SilkS")
		)
		(fp_line
			(start -0.889 1.7018)
			(end 0.889 1.7018)
			(stroke
				(width 0.1524)
				(type default)
			)
			(layer "F.SilkS")
		)
		(fp_line
			(start 0.889 -1.7018)
			(end -0.889 -1.7018)
			(stroke
				(width 0.1524)
				(type default)
			)
			(layer "F.SilkS")
		)
		(fp_line
			(start 0.889 -1.7018)
			(end 0.889 -0.381)
			(stroke
				(width 0.1524)
				(type default)
			)
			(layer "F.SilkS")
		)
		(fp_line
			(start 0.889 1.7018)
			(end 0.889 -0.508)
			(stroke
				(width 0.1524)
				(type default)
			)
			(layer "F.SilkS")
		)
		(fp_poly
			(pts
				(xy 0.9652 -1.778) (xy 0.9652 1.778) (xy -0.9652 1.778) (xy -0.9652 -1.778)
			)
			(stroke
				(width 0)
				(type default)
			)
			(fill no)
			(layer "F.CrtYd")
		)
		(fp_rect
			(start -0.9652 1.778)
			(end 0.9652 -1.778)
			(stroke
				(width 0)
				(type default)
			)
			(fill no)
			(layer "F.Fab")
		)
		(pad "1" smd rect
			(at 0 -0.9652)
			(size 1.397 1.143)
			(layers "F.Cu" "F.Mask" "F.Paste")
			(net "P12V_SSD0")
		)
		(pad "2" smd rect
			(at 0 0.9652)
			(size 1.397 1.143)
			(layers "F.Cu" "F.Mask" "F.Paste")
			(net "P12V_MOST0_GATE_D")
		)
	)
	(footprint ""
		(layer "F.Cu")
		(at 234.061 -143.637 -90)
		(property "Reference" "R9443"
			(at 0 0 270)
			(layer "F.SilkS")
			(hide yes)
			(effects
				(font
					(size 1.27 1.27)
				)
			)
		)
		(property "Value" "100R2J-2-GP"
			(at 0.064008 -3.993896 270)
			(unlocked yes)
			(layer "F.Fab")
			(hide yes)
			(effects
				(font
					(size 1.016 1.016)
					(thickness 0.1524)
				)
			)
		)
		(property "Device Type" "R402H14"
			(at 0.064008 -5.517896 270)
			(unlocked yes)
			(layer "F.Fab")
			(hide yes)
			(effects
				(font
					(size 1.016 1.016)
					(thickness 0.1524)
				)
			)
		)
		(duplicate_pad_numbers_are_jumpers no)
		(fp_line
			(start -0.508 -0.9398)
			(end -0.508 0.9398)
			(stroke
				(width 0.1524)
				(type default)
			)
			(layer "F.SilkS")
		)
		(fp_line
			(start 0.508 -0.9398)
			(end -0.508 -0.9398)
			(stroke
				(width 0.1524)
				(type default)
			)
			(layer "F.SilkS")
		)
		(fp_rect
			(start -0.508 0.9398)
			(end 0.508 -0.9398)
			(stroke
				(width 0)
				(type default)
			)
			(fill no)
			(layer "F.CrtYd")
		)
		(fp_rect
			(start -0.508 0.9398)
			(end 0.508 -0.9398)
			(stroke
				(width 0)
				(type default)
			)
			(fill no)
			(layer "F.Fab")
		)
		(pad "1" smd custom
			(at 0 -0.4445 270)
			(size 0.1397 0.1397)
			(layers "F.Cu" "F.Mask" "F.Paste")
			(net "P3V3")
			(options
				(clearance outline)
				(anchor circle)
			)
			(primitives
				(gr_poly
					(pts
						(arc
							(start -0.1778 -0.2794)
							(mid -0.249642 -0.249642)
							(end -0.2794 -0.1778)
						)
						(arc
							(start -0.2794 0.1778)
							(mid -0.249642 0.249642)
							(end -0.1778 0.2794)
						)
						(arc
							(start 0.1778 0.2794)
							(mid 0.249642 0.249642)
							(end 0.2794 0.1778)
						)
						(arc
							(start 0.2794 -0.1778)
							(mid 0.249642 -0.249642)
							(end 0.1778 -0.2794)
						)
					)
					(width 0)
					(fill yes)
				)
			)
		)
		(pad "2" smd custom
			(at 0 0.4445 270)
			(size 0.1397 0.1397)
			(layers "F.Cu" "F.Mask" "F.Paste")
			(net "DRV_ACT_3")
			(options
				(clearance outline)
				(anchor circle)
			)
			(primitives
				(gr_poly
					(pts
						(arc
							(start -0.1778 -0.2794)
							(mid -0.249642 -0.249642)
							(end -0.2794 -0.1778)
						)
						(arc
							(start -0.2794 0.1778)
							(mid -0.249642 0.249642)
							(end -0.1778 0.2794)
						)
						(arc
							(start 0.1778 0.2794)
							(mid 0.249642 0.249642)
							(end 0.2794 0.1778)
						)
						(arc
							(start 0.2794 -0.1778)
							(mid 0.249642 -0.249642)
							(end 0.1778 -0.2794)
						)
					)
					(width 0)
					(fill yes)
				)
			)
		)
	)
)
